# BASEBOARD_FAB2 (Tioga Pass) — schematic netlist excerpt (pin names and nets, part order shuffled) for the footprints in the layout excerpt that follows; sources: Cadence DE-HDL packaged netlist, KiCad conversion of Wiwynn_Tioga_Pass_MB.brd

EU4D5  PXE1110B  IC  pkg QFN  page 213
  DNC(0)  = NC
  DNC(1)  = NC
  BPWM1  = NC
  DNC(2)  = NC
  APWM1  = VR_PVCCIO_CPU1_PWM1
  SDA  = SMB_VR_STBY_LVC3_SDA
  SCL  = SMB_VR_STBY_LVC3_SCL
  RESET_N  = NC
  AVRRDY  = PWRGD_PVCCIO_CPU1_R
  AVREN  = VR_PVCCIO_CPU1_EN
  VRHOT_N  = IRQ_PVCCIO_CPU1_VRHOT_N
  PINALRT_N  = NC
  MP0  = NC
  MP1  = NC
  VCLK  = SVID_CLK_PVCCIO_CPU1
  VDIO  = SVID_VDIO_PVCCIO_CPU1
  VALRT_N  = SVID_ALERT_PVCCIO_CPU1
  MP2  = NC
  AVSEN  = VR_PVCCIO_CPU1_AVSP
  AVREF  = VSENSE_PVCCIO_CPU1_AVSN
  AIREF1  = VR_PVCCIO_CPU1_AIREF1
  AISEN1  = ISENSE_PVCCIO_CPU1_PH1_IMON
  GND(1)  = GND
  DNC(3)  = NC
  BIREF1  = NC
  BISEN1  = GND
  GND(0)  = GND
  DNC(4)  = NC
  BVSEN  = NC
  BVREF  = NC
  MP3  = NC
  MP4  = PU_VR_PVCCIO_CPU1_FAULT1
  XADDR2  = VR_PVCCIO_CPU1_XADDR2
  BTSEN  = NC
  ATSEN  = A_TSENSE_PVCCIO_CPU1
  XADDR1  = VR_PVCCIO_CPU1_XADDR1
  VINSEN  = VR_PVCCIO_CPU1_VINSEN
  IINSEN  = NC
  VDD  = VR_PVCCIO_CPU1_VDD
  VD12  = VR_PVCCIO_CPU1_VD12
  THPAD  = GND

(kicad_pcb
	(version 20260206)
	(generator "pcbnew")
	(generator_version "10.0")
	(general
		(thickness 1.6)
		(legacy_teardrops no)
	)
	(paper "A4")
	(title_block
		(title "Wiwynn_Tioga_Pass_MB.brd")
		(comment 1 "Tioga Pass / footprint 313 of 4770 (EU4D5), pads 18-34 of 41")
	)
	(layers
		(0 "F.Cu" signal "TOP")
		(4 "In1.Cu" signal "L2GND")
		(6 "In2.Cu" signal "L3")
		(8 "In3.Cu" signal "L4GND")
		(10 "In4.Cu" signal "L5")
		(12 "In5.Cu" signal "L6GND")
		(14 "In6.Cu" signal "L7VCC")
		(16 "In7.Cu" signal "L8VCC")
		(18 "In8.Cu" signal "L9GND")
		(20 "In9.Cu" signal "L10")
		(22 "In10.Cu" signal "L11GND")
		(24 "In11.Cu" signal "L12")
		(26 "In12.Cu" signal "L13GND")
		(2 "B.Cu" signal "BOTTOM")
		(9 "F.Adhes" user "F.Adhesive")
		(11 "B.Adhes" user "B.Adhesive")
		(13 "F.Paste" user "Package Geometry/Pastemask Top")
		(15 "B.Paste" user "Package Geometry/Pastemask Bottom")
		(5 "F.SilkS" user "Ref Des/Silkscreen Top")
		(7 "B.SilkS" user "Ref Des/Silkscreen Bottom")
		(1 "F.Mask" user "Board Geometry/Soldermask Top")
		(3 "B.Mask" user "Board Geometry/Soldermask Bottom")
		(17 "Dwgs.User" user "User.Drawings")
		(19 "Cmts.User" user "User.Comments")
		(21 "Eco1.User" user "User.Eco1")
		(23 "Eco2.User" user "User.Eco2")
		(25 "Edge.Cuts" user "Board Geometry/Outline")
		(27 "Margin" user)
		(31 "F.CrtYd" user "Package Geometry/Place Bound Top")
		(29 "B.CrtYd" user "Package Geometry/Place Bound Bottom")
		(35 "F.Fab" user "Ref Des/Assembly Top")
		(33 "B.Fab" user "Ref Des/Assembly Bottom")
	)
	(footprint ""
		(layer "F.Cu")
		(at 169.1894 -66.802 -90)
		(property "Reference" "EU4D5"
			(at 0.6096 -3.60807 90)
			(unlocked yes)
			(layer "F.SilkS")
			(effects
				(font
					(size 0.7874 0.5842)
					(thickness 0.1524)
				)
				(justify left)
			)
		)
		(property "Value" ""
			(at 0 0 270)
			(layer "F.Fab")
			(effects
				(font
					(size 1.27 1.27)
				)
			)
		)
		(duplicate_pad_numbers_are_jumpers no)
		(pad "18" smd custom
			(at 0.999998 2.4511 270)
			(size 0.0508 0.0508)
			(layers "F.Cu" "F.Mask" "F.Paste")
			(net "Net_302")
			(options
				(clearance outline)
				(anchor circle)
			)
			(primitives
				(gr_poly
					(pts
						(arc
							(start -0.1016 -0.254)
							(mid 0 -0.3556)
							(end 0.1016 -0.254)
						)
						(xy 0.1016 0.3556) (xy -0.1016 0.3556)
					)
					(width 0)
					(fill yes)
				)
			)
		)
		(pad "19" smd custom
			(at 1.400048 2.4511 270)
			(size 0.0508 0.0508)
			(layers "F.Cu" "F.Mask" "F.Paste")
			(net "VR_PVCCIO_CPU1_AVSP")
			(options
				(clearance outline)
				(anchor circle)
			)
			(primitives
				(gr_poly
					(pts
						(arc
							(start -0.1016 -0.254)
							(mid 0 -0.3556)
							(end 0.1016 -0.254)
						)
						(xy 0.1016 0.3556) (xy -0.1016 0.3556)
					)
					(width 0)
					(fill yes)
				)
			)
		)
		(pad "20" smd custom
			(at 1.800098 2.4511 270)
			(size 0.0508 0.0508)
			(layers "F.Cu" "F.Mask" "F.Paste")
			(net "VSENSE_PVCCIO_CPU1_AVSN")
			(options
				(clearance outline)
				(anchor circle)
			)
			(primitives
				(gr_poly
					(pts
						(arc
							(start -0.1016 -0.254)
							(mid 0 -0.3556)
							(end 0.1016 -0.254)
						)
						(xy 0.1016 0.3556) (xy -0.1016 0.3556)
					)
					(width 0)
					(fill yes)
				)
			)
		)
		(pad "21" smd custom
			(at 2.4511 1.800098 270)
			(size 0.0508 0.0508)
			(layers "F.Cu" "F.Mask" "F.Paste")
			(net "VR_PVCCIO_CPU1_AIREF1")
			(options
				(clearance outline)
				(anchor circle)
			)
			(primitives
				(gr_poly
					(pts
						(arc
							(start -0.254 0.1016)
							(mid -0.3556 0)
							(end -0.254 -0.1016)
						)
						(xy 0.3556 -0.1016) (xy 0.3556 0.1016)
					)
					(width 0)
					(fill yes)
				)
			)
		)
		(pad "22" smd custom
			(at 2.4511 1.400048 270)
			(size 0.0508 0.0508)
			(layers "F.Cu" "F.Mask" "F.Paste")
			(net "ISENSE_PVCCIO_CPU1_PH1_IMON")
			(options
				(clearance outline)
				(anchor circle)
			)
			(primitives
				(gr_poly
					(pts
						(arc
							(start -0.254 0.1016)
							(mid -0.3556 0)
							(end -0.254 -0.1016)
						)
						(xy 0.3556 -0.1016) (xy 0.3556 0.1016)
					)
					(width 0)
					(fill yes)
				)
			)
		)
		(pad "23" smd custom
			(at 2.4511 0.999998 270)
			(size 0.0508 0.0508)
			(layers "F.Cu" "F.Mask" "F.Paste")
			(net "GND")
			(options
				(clearance outline)
				(anchor circle)
			)
			(primitives
				(gr_poly
					(pts
						(arc
							(start -0.254 0.1016)
							(mid -0.3556 0)
							(end -0.254 -0.1016)
						)
						(xy 0.3556 -0.1016) (xy 0.3556 0.1016)
					)
					(width 0)
					(fill yes)
				)
			)
		)
		(pad "24" smd custom
			(at 2.4511 0.599948 270)
			(size 0.0508 0.0508)
			(layers "F.Cu" "F.Mask" "F.Paste")
			(net "Net_339")
			(options
				(clearance outline)
				(anchor circle)
			)
			(primitives
				(gr_poly
					(pts
						(arc
							(start -0.254 0.1016)
							(mid -0.3556 0)
							(end -0.254 -0.1016)
						)
						(xy 0.3556 -0.1016) (xy 0.3556 0.1016)
					)
					(width 0)
					(fill yes)
				)
			)
		)
		(pad "25" smd custom
			(at 2.4511 0.199898 270)
			(size 0.0508 0.0508)
			(layers "F.Cu" "F.Mask" "F.Paste")
			(net "Net_258")
			(options
				(clearance outline)
				(anchor circle)
			)
			(primitives
				(gr_poly
					(pts
						(arc
							(start -0.254 0.1016)
							(mid -0.3556 0)
							(end -0.254 -0.1016)
						)
						(xy 0.3556 -0.1016) (xy 0.3556 0.1016)
					)
					(width 0)
					(fill yes)
				)
			)
		)
		(pad "26" smd custom
			(at 2.4511 -0.199898 270)
			(size 0.0508 0.0508)
			(layers "F.Cu" "F.Mask" "F.Paste")
			(net "GND")
			(options
				(clearance outline)
				(anchor circle)
			)
			(primitives
				(gr_poly
					(pts
						(arc
							(start -0.254 0.1016)
							(mid -0.3556 0)
							(end -0.254 -0.1016)
						)
						(xy 0.3556 -0.1016) (xy 0.3556 0.1016)
					)
					(width 0)
					(fill yes)
				)
			)
		)
		(pad "27" smd custom
			(at 2.4511 -0.599948 270)
			(size 0.0508 0.0508)
			(layers "F.Cu" "F.Mask" "F.Paste")
			(net "GND")
			(options
				(clearance outline)
				(anchor circle)
			)
			(primitives
				(gr_poly
					(pts
						(arc
							(start -0.254 0.1016)
							(mid -0.3556 0)
							(end -0.254 -0.1016)
						)
						(xy 0.3556 -0.1016) (xy 0.3556 0.1016)
					)
					(width 0)
					(fill yes)
				)
			)
		)
		(pad "28" smd custom
			(at 2.4511 -0.999998 270)
			(size 0.0508 0.0508)
			(layers "F.Cu" "F.Mask" "F.Paste")
			(net "Net_340")
			(options
				(clearance outline)
				(anchor circle)
			)
			(primitives
				(gr_poly
					(pts
						(arc
							(start -0.254 0.1016)
							(mid -0.3556 0)
							(end -0.254 -0.1016)
						)
						(xy 0.3556 -0.1016) (xy 0.3556 0.1016)
					)
					(width 0)
					(fill yes)
				)
			)
		)
		(pad "29" smd custom
			(at 2.4511 -1.400048 270)
			(size 0.0508 0.0508)
			(layers "F.Cu" "F.Mask" "F.Paste")
			(net "Net_261")
			(options
				(clearance outline)
				(anchor circle)
			)
			(primitives
				(gr_poly
					(pts
						(arc
							(start -0.254 0.1016)
							(mid -0.3556 0)
							(end -0.254 -0.1016)
						)
						(xy 0.3556 -0.1016) (xy 0.3556 0.1016)
					)
					(width 0)
					(fill yes)
				)
			)
		)
		(pad "30" smd custom
			(at 2.4511 -1.800098 270)
			(size 0.0508 0.0508)
			(layers "F.Cu" "F.Mask" "F.Paste")
			(net "Net_260")
			(options
				(clearance outline)
				(anchor circle)
			)
			(primitives
				(gr_poly
					(pts
						(arc
							(start -0.254 0.1016)
							(mid -0.3556 0)
							(end -0.254 -0.1016)
						)
						(xy 0.3556 -0.1016) (xy 0.3556 0.1016)
					)
					(width 0)
					(fill yes)
				)
			)
		)
		(pad "31" smd custom
			(at 1.800098 -2.4511 270)
			(size 0.0508 0.0508)
			(layers "F.Cu" "F.Mask" "F.Paste")
			(net "Net_303")
			(options
				(clearance outline)
				(anchor circle)
			)
			(primitives
				(gr_poly
					(pts
						(arc
							(start 0.1016 0.254)
							(mid 0 0.3556)
							(end -0.1016 0.254)
						)
						(xy -0.1016 -0.3556) (xy 0.1016 -0.3556)
					)
					(width 0)
					(fill yes)
				)
			)
		)
		(pad "32" smd custom
			(at 1.400048 -2.4511 270)
			(size 0.0508 0.0508)
			(layers "F.Cu" "F.Mask" "F.Paste")
			(net "PU_VR_PVCCIO_CPU1_FAULT1")
			(options
				(clearance outline)
				(anchor circle)
			)
			(primitives
				(gr_poly
					(pts
						(arc
							(start 0.1016 0.254)
							(mid 0 0.3556)
							(end -0.1016 0.254)
						)
						(xy -0.1016 -0.3556) (xy 0.1016 -0.3556)
					)
					(width 0)
					(fill yes)
				)
			)
		)
		(pad "33" smd custom
			(at 0.999998 -2.4511 270)
			(size 0.0508 0.0508)
			(layers "F.Cu" "F.Mask" "F.Paste")
			(net "VR_PVCCIO_CPU1_XADDR2")
			(options
				(clearance outline)
				(anchor circle)
			)
			(primitives
				(gr_poly
					(pts
						(arc
							(start 0.1016 0.254)
							(mid 0 0.3556)
							(end -0.1016 0.254)
						)
						(xy -0.1016 -0.3556) (xy 0.1016 -0.3556)
					)
					(width 0)
					(fill yes)
				)
			)
		)
		(pad "34" smd custom
			(at 0.599948 -2.4511 270)
			(size 0.0508 0.0508)
			(layers "F.Cu" "F.Mask" "F.Paste")
			(net "Net_259")
			(options
				(clearance outline)
				(anchor circle)
			)
			(primitives
				(gr_poly
					(pts
						(arc
							(start 0.1016 0.254)
							(mid 0 0.3556)
							(end -0.1016 0.254)
						)
						(xy -0.1016 -0.3556) (xy 0.1016 -0.3556)
					)
					(width 0)
					(fill yes)
				)
			)
		)
	)
)
